# S9S_MB_2U (Grand Teton) — schematic netlist excerpt (pin names and nets, part order shuffled) for the footprints in the layout excerpt that follows; sources: Cadence DE-HDL packaged netlist, KiCad conversion of 03242023_DA0F0TMBIJ0_F0T_Motherboard_J_brd_V01_OCP.brd

C1571  Q_CAP_DIFFBUS  DIFF BUS_0.22UF 6.3V 20% X6S  pkg C0201  page 175 : \1\ = P5E_CPU0_PE4_TX_C_DP<4> ; \2\ = P5E_CPU0_PE4_TX_DP<4>
R4492  Q_RES  10K 1% CHIP  pkg 0402LF  page 211 : A = CLK_9ZXL045_HIBW ; B = GND
R3475  Q_RES  4.7K 5% CHIP  pkg 0402LF  page 147 : A = P3V3_AUX ; B = GPU_PRSNT_N_ISO

(kicad_pcb
	(version 20260206)
	(generator "pcbnew")
	(generator_version "10.0")
	(general
		(thickness 1.6)
		(legacy_teardrops no)
	)
	(paper "A4")
	(title_block
		(title "03242023_DA0F0TMBIJ0_F0T_Motherboard_J_brd_V01_OCP.brd")
		(comment 1 "Grand Teton / footprints 2668-2670 of 6105")
	)
	(layers
		(0 "F.Cu" signal "TOP")
		(4 "In1.Cu" signal "GND")
		(6 "In2.Cu" signal "IN1")
		(8 "In3.Cu" signal "GND1")
		(10 "In4.Cu" signal "IN2")
		(12 "In5.Cu" signal "GND2")
		(14 "In6.Cu" signal "IN3")
		(16 "In7.Cu" signal "GND3")
		(18 "In8.Cu" signal "VCC")
		(20 "In9.Cu" signal "VCC1")
		(22 "In10.Cu" signal "GND4")
		(24 "In11.Cu" signal "IN4")
		(26 "In12.Cu" signal "GND5")
		(28 "In13.Cu" signal "IN5")
		(30 "In14.Cu" signal "GND6")
		(32 "In15.Cu" signal "IN6")
		(34 "In16.Cu" signal "GND7")
		(2 "B.Cu" signal "BOTTOM")
		(9 "F.Adhes" user "F.Adhesive")
		(11 "B.Adhes" user "B.Adhesive")
		(13 "F.Paste" user "Package Geometry/Pastemask Top")
		(15 "B.Paste" user "Package Geometry/Pastemask Bottom")
		(5 "F.SilkS" user "Ref Des/Silkscreen Top")
		(7 "B.SilkS" user "Ref Des/Silkscreen Bottom")
		(1 "F.Mask" user "Board Geometry/Soldermask Top")
		(3 "B.Mask" user "Board Geometry/Soldermask Bottom")
		(17 "Dwgs.User" user "User.Drawings")
		(19 "Cmts.User" user "User.Comments")
		(21 "Eco1.User" user "User.Eco1")
		(23 "Eco2.User" user "User.Eco2")
		(25 "Edge.Cuts" user "Board Geometry/Outline")
		(27 "Margin" user)
		(31 "F.CrtYd" user "Package Geometry/Place Bound Top")
		(29 "B.CrtYd" user "Package Geometry/Place Bound Bottom")
		(35 "F.Fab" user "Ref Des/Assembly Top")
		(33 "B.Fab" user "Ref Des/Assembly Bottom")
	)
	(footprint ""
		(layer "F.Cu")
		(at 118.83898 -411.131004)
		(property "Reference" "R4492"
			(at 0 0 0)
			(layer "F.SilkS")
			(hide yes)
			(effects
				(font
					(size 1.27 1.27)
				)
			)
		)
		(property "Value" ""
			(at 0 0 0)
			(layer "F.Fab")
			(effects
				(font
					(size 1.27 1.27)
				)
			)
		)
		(duplicate_pad_numbers_are_jumpers no)
		(fp_line
			(start -0.7874 -0.4064)
			(end 0.7874 -0.4064)
			(stroke
				(width 0.1524)
				(type default)
			)
			(layer "F.SilkS")
		)
		(fp_line
			(start -0.7874 0.4064)
			(end -0.7874 -0.4064)
			(stroke
				(width 0.1524)
				(type default)
			)
			(layer "F.SilkS")
		)
		(fp_line
			(start 0.7874 -0.4064)
			(end 0.7874 0.4064)
			(stroke
				(width 0.1524)
				(type default)
			)
			(layer "F.SilkS")
		)
		(fp_line
			(start 0.7874 0.4064)
			(end -0.7874 0.4064)
			(stroke
				(width 0.1524)
				(type default)
			)
			(layer "F.SilkS")
		)
		(fp_line
			(start -0.67945 -0.305054)
			(end -0.12065 -0.305054)
			(stroke
				(width 0.1)
				(type default)
			)
			(layer "F.Fab")
		)
		(fp_line
			(start -0.67945 0.3048)
			(end -0.67945 -0.305054)
			(stroke
				(width 0.1)
				(type default)
			)
			(layer "F.Fab")
		)
		(fp_line
			(start -0.12065 -0.305054)
			(end -0.12065 -0.2794)
			(stroke
				(width 0.1)
				(type default)
			)
			(layer "F.Fab")
		)
		(fp_line
			(start -0.12065 -0.2794)
			(end 0.12065 -0.2794)
			(stroke
				(width 0.1)
				(type default)
			)
			(layer "F.Fab")
		)
		(fp_line
			(start -0.12065 0.2794)
			(end -0.12065 0.3048)
			(stroke
				(width 0.1)
				(type default)
			)
			(layer "F.Fab")
		)
		(fp_line
			(start -0.12065 0.3048)
			(end -0.67945 0.3048)
			(stroke
				(width 0.1)
				(type default)
			)
			(layer "F.Fab")
		)
		(fp_line
			(start 0.120396 0.2794)
			(end -0.12065 0.2794)
			(stroke
				(width 0.1)
				(type default)
			)
			(layer "F.Fab")
		)
		(fp_line
			(start 0.120396 0.3048)
			(end 0.120396 0.2794)
			(stroke
				(width 0.1)
				(type default)
			)
			(layer "F.Fab")
		)
		(fp_line
			(start 0.12065 -0.3048)
			(end 0.67945 -0.3048)
			(stroke
				(width 0.1)
				(type default)
			)
			(layer "F.Fab")
		)
		(fp_line
			(start 0.12065 -0.2794)
			(end 0.12065 -0.3048)
			(stroke
				(width 0.1)
				(type default)
			)
			(layer "F.Fab")
		)
		(fp_line
			(start 0.67945 -0.3048)
			(end 0.67945 0.3048)
			(stroke
				(width 0.1)
				(type default)
			)
			(layer "F.Fab")
		)
		(fp_line
			(start 0.67945 0.3048)
			(end 0.120396 0.3048)
			(stroke
				(width 0.1)
				(type default)
			)
			(layer "F.Fab")
		)
		(pad "1" smd circle
			(at -0.40005 0)
			(size 0 0)
			(layers "F.Cu" "F.Mask" "F.Paste")
			(net "CLK_9ZXL045_HIBW")
		)
		(pad "2" smd circle
			(at 0.40005 0)
			(size 0 0)
			(layers "F.Cu" "F.Mask" "F.Paste")
			(net "GND")
		)
	)
	(footprint ""
		(layer "F.Cu")
		(at 26.6446 -409.0416 90)
		(property "Reference" "R3475"
			(at 0 0 90)
			(layer "F.SilkS")
			(hide yes)
			(effects
				(font
					(size 1.27 1.27)
				)
			)
		)
		(property "Value" ""
			(at 0 0 90)
			(layer "F.Fab")
			(effects
				(font
					(size 1.27 1.27)
				)
			)
		)
		(duplicate_pad_numbers_are_jumpers no)
		(fp_line
			(start 0.7874 -0.4064)
			(end 0.7874 0.4064)
			(stroke
				(width 0.1524)
				(type default)
			)
			(layer "F.SilkS")
		)
		(fp_line
			(start -0.7874 -0.4064)
			(end 0.7874 -0.4064)
			(stroke
				(width 0.1524)
				(type default)
			)
			(layer "F.SilkS")
		)
		(fp_line
			(start 0.7874 0.4064)
			(end -0.7874 0.4064)
			(stroke
				(width 0.1524)
				(type default)
			)
			(layer "F.SilkS")
		)
		(fp_line
			(start -0.7874 0.4064)
			(end -0.7874 -0.4064)
			(stroke
				(width 0.1524)
				(type default)
			)
			(layer "F.SilkS")
		)
		(fp_line
			(start -0.12065 -0.305054)
			(end -0.12065 -0.2794)
			(stroke
				(width 0.1)
				(type default)
			)
			(layer "F.Fab")
		)
		(fp_line
			(start -0.67945 -0.305054)
			(end -0.12065 -0.305054)
			(stroke
				(width 0.1)
				(type default)
			)
			(layer "F.Fab")
		)
		(fp_line
			(start 0.67945 -0.3048)
			(end 0.67945 0.3048)
			(stroke
				(width 0.1)
				(type default)
			)
			(layer "F.Fab")
		)
		(fp_line
			(start 0.12065 -0.3048)
			(end 0.67945 -0.3048)
			(stroke
				(width 0.1)
				(type default)
			)
			(layer "F.Fab")
		)
		(fp_line
			(start 0.12065 -0.2794)
			(end 0.12065 -0.3048)
			(stroke
				(width 0.1)
				(type default)
			)
			(layer "F.Fab")
		)
		(fp_line
			(start -0.12065 -0.2794)
			(end 0.12065 -0.2794)
			(stroke
				(width 0.1)
				(type default)
			)
			(layer "F.Fab")
		)
		(fp_line
			(start 0.120396 0.2794)
			(end -0.12065 0.2794)
			(stroke
				(width 0.1)
				(type default)
			)
			(layer "F.Fab")
		)
		(fp_line
			(start -0.12065 0.2794)
			(end -0.12065 0.3048)
			(stroke
				(width 0.1)
				(type default)
			)
			(layer "F.Fab")
		)
		(fp_line
			(start 0.67945 0.3048)
			(end 0.120396 0.3048)
			(stroke
				(width 0.1)
				(type default)
			)
			(layer "F.Fab")
		)
		(fp_line
			(start 0.120396 0.3048)
			(end 0.120396 0.2794)
			(stroke
				(width 0.1)
				(type default)
			)
			(layer "F.Fab")
		)
		(fp_line
			(start -0.12065 0.3048)
			(end -0.67945 0.3048)
			(stroke
				(width 0.1)
				(type default)
			)
			(layer "F.Fab")
		)
		(fp_line
			(start -0.67945 0.3048)
			(end -0.67945 -0.305054)
			(stroke
				(width 0.1)
				(type default)
			)
			(layer "F.Fab")
		)
		(pad "1" smd circle
			(at -0.40005 0 90)
			(size 0 0)
			(layers "F.Cu" "F.Mask" "F.Paste")
			(net "P3V3_AUX")
		)
		(pad "2" smd circle
			(at 0.40005 0 90)
			(size 0 0)
			(layers "F.Cu" "F.Mask" "F.Paste")
			(net "GPU_PRSNT_N_ISO")
		)
	)
	(footprint ""
		(layer "F.Cu")
		(at 317.122048 -402.371052 -90)
		(property "Reference" "C1571"
			(at 0 0 270)
			(layer "F.SilkS")
			(hide yes)
			(effects
				(font
					(size 1.27 1.27)
				)
			)
		)
		(property "Value" ""
			(at 0 0 270)
			(layer "F.Fab")
			(effects
				(font
					(size 1.27 1.27)
				)
			)
		)
		(duplicate_pad_numbers_are_jumpers no)
		(fp_line
			(start -0.299974 0.150114)
			(end -0.299974 -0.150114)
			(stroke
				(width 0.1)
				(type default)
			)
			(layer "F.Fab")
		)
		(fp_line
			(start 0.299974 0.150114)
			(end -0.299974 0.150114)
			(stroke
				(width 0.1)
				(type default)
			)
			(layer "F.Fab")
		)
		(fp_line
			(start -0.299974 -0.150114)
			(end 0.299974 -0.150114)
			(stroke
				(width 0.1)
				(type default)
			)
			(layer "F.Fab")
		)
		(fp_line
			(start 0.299974 -0.150114)
			(end 0.299974 0.150114)
			(stroke
				(width 0.1)
				(type default)
			)
			(layer "F.Fab")
		)
		(pad "1" smd rect
			(at -0.2667 0 270)
			(size 0.3048 0.381)
			(layers "F.Cu" "F.Mask" "F.Paste")
			(net "P5E_CPU0_PE4_TX_C_DP<4>")
		)
		(pad "2" smd rect
			(at 0.2667 0 270)
			(size 0.3048 0.381)
			(layers "F.Cu" "F.Mask" "F.Paste")
			(net "P5E_CPU0_PE4_TX_DP<4>")
		)
	)
)
